(kicad_pcb
	(version 20260206)
	(generator "pcbnew")
	(generator_version "10.0")
	(general
		(thickness 1.6)
		(legacy_teardrops no)
	)
	(paper "A4")
	(title_block
		(title "03242023_DA0F0TMBIJ0_F0T_Motherboard_J_brd_V01_OCP.brd")
		(comment 1 "Grand Teton / footprints 5925-5930 of 6105")
	)
	(layers
		(0 "F.Cu" signal "TOP")
		(4 "In1.Cu" signal "GND")
		(6 "In2.Cu" signal "IN1")
		(8 "In3.Cu" signal "GND1")
		(10 "In4.Cu" signal "IN2")
		(12 "In5.Cu" signal "GND2")
		(14 "In6.Cu" signal "IN3")
		(16 "In7.Cu" signal "GND3")
		(18 "In8.Cu" signal "VCC")
		(20 "In9.Cu" signal "VCC1")
		(22 "In10.Cu" signal "GND4")
		(24 "In11.Cu" signal "IN4")
		(26 "In12.Cu" signal "GND5")
		(28 "In13.Cu" signal "IN5")
		(30 "In14.Cu" signal "GND6")
		(32 "In15.Cu" signal "IN6")
		(34 "In16.Cu" signal "GND7")
		(2 "B.Cu" signal "BOTTOM")
		(9 "F.Adhes" user "F.Adhesive")
		(11 "B.Adhes" user "B.Adhesive")
		(13 "F.Paste" user "Package Geometry/Pastemask Top")
		(15 "B.Paste" user "Package Geometry/Pastemask Bottom")
		(5 "F.SilkS" user "Ref Des/Silkscreen Top")
		(7 "B.SilkS" user "Ref Des/Silkscreen Bottom")
		(1 "F.Mask" user "Board Geometry/Soldermask Top")
		(3 "B.Mask" user "Board Geometry/Soldermask Bottom")
		(17 "Dwgs.User" user "User.Drawings")
		(19 "Cmts.User" user "User.Comments")
		(21 "Eco1.User" user "User.Eco1")
		(23 "Eco2.User" user "User.Eco2")
		(25 "Edge.Cuts" user "Board Geometry/Outline")
		(27 "Margin" user)
		(31 "F.CrtYd" user "Package Geometry/Place Bound Top")
		(29 "B.CrtYd" user "Package Geometry/Place Bound Bottom")
		(35 "F.Fab" user "Ref Des/Assembly Top")
		(33 "B.Fab" user "Ref Des/Assembly Bottom")
	)
	(footprint ""
		(layer "B.Cu")
		(at 205.28788 -35.956748 90)
		(property "Reference" "C2022"
			(at 0 0 90)
			(layer "B.SilkS")
			(hide yes)
			(effects
				(font
					(size 1.27 1.27)
				)
				(justify mirror)
			)
		)
		(property "Value" ""
			(at 0 0 90)
			(layer "B.Fab")
			(effects
				(font
					(size 1.27 1.27)
				)
				(justify mirror)
			)
		)
		(duplicate_pad_numbers_are_jumpers no)
		(fp_line
			(start 0.7874 -0.4064)
			(end -0.7874 -0.4064)
			(stroke
				(width 0.1524)
				(type default)
			)
			(layer "B.SilkS")
		)
		(fp_line
			(start -0.7874 -0.4064)
			(end -0.7874 0.4064)
			(stroke
				(width 0.1524)
				(type default)
			)
			(layer "B.SilkS")
		)
		(fp_line
			(start 0.7874 0.4064)
			(end 0.7874 -0.4064)
			(stroke
				(width 0.1524)
				(type default)
			)
			(layer "B.SilkS")
		)
		(fp_line
			(start -0.7874 0.4064)
			(end 0.7874 0.4064)
			(stroke
				(width 0.1524)
				(type default)
			)
			(layer "B.SilkS")
		)
		(fp_line
			(start 0.67945 -0.305054)
			(end 0.12065 -0.305054)
			(stroke
				(width 0.1)
				(type default)
			)
			(layer "B.Fab")
		)
		(fp_line
			(start 0.12065 -0.305054)
			(end 0.12065 -0.2794)
			(stroke
				(width 0.1)
				(type default)
			)
			(layer "B.Fab")
		)
		(fp_line
			(start -0.12065 -0.3048)
			(end -0.67945 -0.3048)
			(stroke
				(width 0.1)
				(type default)
			)
			(layer "B.Fab")
		)
		(fp_line
			(start -0.67945 -0.3048)
			(end -0.67945 0.3048)
			(stroke
				(width 0.1)
				(type default)
			)
			(layer "B.Fab")
		)
		(fp_line
			(start 0.12065 -0.2794)
			(end -0.12065 -0.2794)
			(stroke
				(width 0.1)
				(type default)
			)
			(layer "B.Fab")
		)
		(fp_line
			(start -0.12065 -0.2794)
			(end -0.12065 -0.3048)
			(stroke
				(width 0.1)
				(type default)
			)
			(layer "B.Fab")
		)
		(fp_line
			(start 0.12065 0.2794)
			(end 0.12065 0.3048)
			(stroke
				(width 0.1)
				(type default)
			)
			(layer "B.Fab")
		)
		(fp_line
			(start -0.120396 0.2794)
			(end 0.12065 0.2794)
			(stroke
				(width 0.1)
				(type default)
			)
			(layer "B.Fab")
		)
		(fp_line
			(start 0.67945 0.3048)
			(end 0.67945 -0.305054)
			(stroke
				(width 0.1)
				(type default)
			)
			(layer "B.Fab")
		)
		(fp_line
			(start 0.12065 0.3048)
			(end 0.67945 0.3048)
			(stroke
				(width 0.1)
				(type default)
			)
			(layer "B.Fab")
		)
		(fp_line
			(start -0.120396 0.3048)
			(end -0.120396 0.2794)
			(stroke
				(width 0.1)
				(type default)
			)
			(layer "B.Fab")
		)
		(fp_line
			(start -0.67945 0.3048)
			(end -0.120396 0.3048)
			(stroke
				(width 0.1)
				(type default)
			)
			(layer "B.Fab")
		)
		(pad "1" smd circle
			(at 0.40005 0 270)
			(size 0 0)
			(layers "B.Cu" "B.Mask" "B.Paste")
			(net "VSENSE_P12V_INA230_5_INP")
		)
		(pad "2" smd circle
			(at -0.40005 0 270)
			(size 0 0)
			(layers "B.Cu" "B.Mask" "B.Paste")
			(net "VSENSE_P12V_INA230_5_INN")
		)
	)
	(footprint ""
		(layer "B.Cu")
		(at 131.74726 -27.3177)
		(property "Reference" "C2350"
			(at 0 0 0)
			(layer "B.SilkS")
			(hide yes)
			(effects
				(font
					(size 1.27 1.27)
				)
				(justify mirror)
			)
		)
		(property "Value" ""
			(at 0 0 0)
			(layer "B.Fab")
			(effects
				(font
					(size 1.27 1.27)
				)
				(justify mirror)
			)
		)
		(duplicate_pad_numbers_are_jumpers no)
		(fp_line
			(start -0.40005 0.4064)
			(end 0.40005 0.4064)
			(stroke
				(width 0.1524)
				(type default)
			)
			(layer "B.SilkS")
		)
		(fp_line
			(start 0.40005 -0.4064)
			(end -0.40005 -0.4064)
			(stroke
				(width 0.1524)
				(type default)
			)
			(layer "B.SilkS")
		)
		(fp_line
			(start -0.6858 -0.3048)
			(end -0.6858 0.3048)
			(stroke
				(width 0.1)
				(type default)
			)
			(layer "B.Fab")
		)
		(fp_line
			(start -0.6858 0.3048)
			(end -0.1016 0.3048)
			(stroke
				(width 0.1)
				(type default)
			)
			(layer "B.Fab")
		)
		(fp_line
			(start -0.1016 -0.3048)
			(end -0.6858 -0.3048)
			(stroke
				(width 0.1)
				(type default)
			)
			(layer "B.Fab")
		)
		(fp_line
			(start -0.1016 -0.2794)
			(end -0.1016 -0.3048)
			(stroke
				(width 0.1)
				(type default)
			)
			(layer "B.Fab")
		)
		(fp_line
			(start -0.1016 0.2794)
			(end 0.1016 0.2794)
			(stroke
				(width 0.1)
				(type default)
			)
			(layer "B.Fab")
		)
		(fp_line
			(start -0.1016 0.3048)
			(end -0.1016 0.2794)
			(stroke
				(width 0.1)
				(type default)
			)
			(layer "B.Fab")
		)
		(fp_line
			(start 0.1016 -0.3048)
			(end 0.1016 -0.2794)
			(stroke
				(width 0.1)
				(type default)
			)
			(layer "B.Fab")
		)
		(fp_line
			(start 0.1016 -0.2794)
			(end -0.1016 -0.2794)
			(stroke
				(width 0.1)
				(type default)
			)
			(layer "B.Fab")
		)
		(fp_line
			(start 0.1016 0.2794)
			(end 0.1016 0.3048)
			(stroke
				(width 0.1)
				(type default)
			)
			(layer "B.Fab")
		)
		(fp_line
			(start 0.1016 0.3048)
			(end 0.6858 0.3048)
			(stroke
				(width 0.1)
				(type default)
			)
			(layer "B.Fab")
		)
		(fp_line
			(start 0.6858 -0.3048)
			(end 0.1016 -0.3048)
			(stroke
				(width 0.1)
				(type default)
			)
			(layer "B.Fab")
		)
		(fp_line
			(start 0.6858 0.3048)
			(end 0.6858 -0.3048)
			(stroke
				(width 0.1)
				(type default)
			)
			(layer "B.Fab")
		)
		(pad "1" smd rect
			(at 0.40005 0)
			(size 0.4572 0.508)
			(layers "B.Cu" "B.Mask" "B.Paste")
			(net "USB3_PCH_RX_DN<4>")
		)
		(pad "2" smd rect
			(at -0.40005 0)
			(size 0.4572 0.508)
			(layers "B.Cu" "B.Mask" "B.Paste")
			(net "USB3_PCH_RX_C_DN<4>")
		)
		(zone
			(layer "In16.Cu")
			(hatch none 0.5)
			(connect_pads
				(clearance 0)
			)
			(min_thickness 0.25)
			(keepout
				(tracks not_allowed)
				(vias allowed)
				(pads allowed)
				(copperpour not_allowed)
				(footprints allowed)
			)
			(placement
				(enabled no)
				(sheetname "")
			)
			(fill
				(thermal_gap 0.5)
				(thermal_bridge_width 0.5)
				(island_removal_mode 0)
			)
			(polygon
				(pts
					(xy 131.62661 -27.0129) (xy 131.06781 -27.0129) (xy 131.06781 -27.6225) (xy 131.62661 -27.6225)
				)
			)
		)
		(zone
			(layer "In16.Cu")
			(hatch none 0.5)
			(connect_pads
				(clearance 0)
			)
			(min_thickness 0.25)
			(keepout
				(tracks not_allowed)
				(vias allowed)
				(pads allowed)
				(copperpour not_allowed)
				(footprints allowed)
			)
			(placement
				(enabled no)
				(sheetname "")
			)
			(fill
				(thermal_gap 0.5)
				(thermal_bridge_width 0.5)
				(island_removal_mode 0)
			)
			(polygon
				(pts
					(xy 132.42671 -27.0129) (xy 131.86791 -27.0129) (xy 131.86791 -27.6225) (xy 132.42671 -27.6225)
				)
			)
		)
	)
	(footprint ""
		(layer "B.Cu")
		(at 339.267038 -48.516286 180)
		(property "Reference" "C1200"
			(at 0 0 0)
			(layer "B.SilkS")
			(hide yes)
			(effects
				(font
					(size 1.27 1.27)
				)
				(justify mirror)
			)
		)
		(property "Value" ""
			(at 0 0 0)
			(layer "B.Fab")
			(effects
				(font
					(size 1.27 1.27)
				)
				(justify mirror)
			)
		)
		(duplicate_pad_numbers_are_jumpers no)
		(fp_line
			(start 0.7874 0.4064)
			(end 0.7874 -0.4064)
			(stroke
				(width 0.1524)
				(type default)
			)
			(layer "B.SilkS")
		)
		(fp_line
			(start 0.7874 -0.4064)
			(end -0.7874 -0.4064)
			(stroke
				(width 0.1524)
				(type default)
			)
			(layer "B.SilkS")
		)
		(fp_line
			(start -0.7874 0.4064)
			(end 0.7874 0.4064)
			(stroke
				(width 0.1524)
				(type default)
			)
			(layer "B.SilkS")
		)
		(fp_line
			(start -0.7874 -0.4064)
			(end -0.7874 0.4064)
			(stroke
				(width 0.1524)
				(type default)
			)
			(layer "B.SilkS")
		)
		(fp_line
			(start 0.67945 0.3048)
			(end 0.67945 -0.305054)
			(stroke
				(width 0.1)
				(type default)
			)
			(layer "B.Fab")
		)
		(fp_line
			(start 0.67945 -0.305054)
			(end 0.12065 -0.305054)
			(stroke
				(width 0.1)
				(type default)
			)
			(layer "B.Fab")
		)
		(fp_line
			(start 0.12065 0.3048)
			(end 0.67945 0.3048)
			(stroke
				(width 0.1)
				(type default)
			)
			(layer "B.Fab")
		)
		(fp_line
			(start 0.12065 0.2794)
			(end 0.12065 0.3048)
			(stroke
				(width 0.1)
				(type default)
			)
			(layer "B.Fab")
		)
		(fp_line
			(start 0.12065 -0.2794)
			(end -0.12065 -0.2794)
			(stroke
				(width 0.1)
				(type default)
			)
			(layer "B.Fab")
		)
		(fp_line
			(start 0.12065 -0.305054)
			(end 0.12065 -0.2794)
			(stroke
				(width 0.1)
				(type default)
			)
			(layer "B.Fab")
		)
		(fp_line
			(start -0.120396 0.3048)
			(end -0.120396 0.2794)
			(stroke
				(width 0.1)
				(type default)
			)
			(layer "B.Fab")
		)
		(fp_line
			(start -0.120396 0.2794)
			(end 0.12065 0.2794)
			(stroke
				(width 0.1)
				(type default)
			)
			(layer "B.Fab")
		)
		(fp_line
			(start -0.12065 -0.2794)
			(end -0.12065 -0.3048)
			(stroke
				(width 0.1)
				(type default)
			)
			(layer "B.Fab")
		)
		(fp_line
			(start -0.12065 -0.3048)
			(end -0.67945 -0.3048)
			(stroke
				(width 0.1)
				(type default)
			)
			(layer "B.Fab")
		)
		(fp_line
			(start -0.67945 0.3048)
			(end -0.120396 0.3048)
			(stroke
				(width 0.1)
				(type default)
			)
			(layer "B.Fab")
		)
		(fp_line
			(start -0.67945 -0.3048)
			(end -0.67945 0.3048)
			(stroke
				(width 0.1)
				(type default)
			)
			(layer "B.Fab")
		)
		(pad "1" smd circle
			(at 0.40005 0)
			(size 0 0)
			(layers "B.Cu" "B.Mask" "B.Paste")
			(net "P1V05_PCH_AUX")
		)
		(pad "2" smd circle
			(at -0.40005 0)
			(size 0 0)
			(layers "B.Cu" "B.Mask" "B.Paste")
			(net "GND")
		)
	)
	(footprint ""
		(layer "B.Cu")
		(at 429.391572 -317.39332 90)
		(property "Reference" "R3885"
			(at 0 0 90)
			(layer "B.SilkS")
			(hide yes)
			(effects
				(font
					(size 1.27 1.27)
				)
				(justify mirror)
			)
		)
		(property "Value" ""
			(at 0 0 90)
			(layer "B.Fab")
			(effects
				(font
					(size 1.27 1.27)
				)
				(justify mirror)
			)
		)
		(duplicate_pad_numbers_are_jumpers no)
		(fp_line
			(start 0.7874 -0.4064)
			(end -0.7874 -0.4064)
			(stroke
				(width 0.1524)
				(type default)
			)
			(layer "B.SilkS")
		)
		(fp_line
			(start -0.7874 -0.4064)
			(end -0.7874 0.4064)
			(stroke
				(width 0.1524)
				(type default)
			)
			(layer "B.SilkS")
		)
		(fp_line
			(start 0.7874 0.4064)
			(end 0.7874 -0.4064)
			(stroke
				(width 0.1524)
				(type default)
			)
			(layer "B.SilkS")
		)
		(fp_line
			(start -0.7874 0.4064)
			(end 0.7874 0.4064)
			(stroke
				(width 0.1524)
				(type default)
			)
			(layer "B.SilkS")
		)
		(fp_line
			(start 0.67945 -0.305054)
			(end 0.12065 -0.305054)
			(stroke
				(width 0.1)
				(type default)
			)
			(layer "B.Fab")
		)
		(fp_line
			(start 0.12065 -0.305054)
			(end 0.12065 -0.2794)
			(stroke
				(width 0.1)
				(type default)
			)
			(layer "B.Fab")
		)
		(fp_line
			(start -0.12065 -0.3048)
			(end -0.67945 -0.3048)
			(stroke
				(width 0.1)
				(type default)
			)
			(layer "B.Fab")
		)
		(fp_line
			(start -0.67945 -0.3048)
			(end -0.67945 0.3048)
			(stroke
				(width 0.1)
				(type default)
			)
			(layer "B.Fab")
		)
		(fp_line
			(start 0.12065 -0.2794)
			(end -0.12065 -0.2794)
			(stroke
				(width 0.1)
				(type default)
			)
			(layer "B.Fab")
		)
		(fp_line
			(start -0.12065 -0.2794)
			(end -0.12065 -0.3048)
			(stroke
				(width 0.1)
				(type default)
			)
			(layer "B.Fab")
		)
		(fp_line
			(start 0.12065 0.2794)
			(end 0.12065 0.3048)
			(stroke
				(width 0.1)
				(type default)
			)
			(layer "B.Fab")
		)
		(fp_line
			(start -0.120396 0.2794)
			(end 0.12065 0.2794)
			(stroke
				(width 0.1)
				(type default)
			)
			(layer "B.Fab")
		)
		(fp_line
			(start 0.67945 0.3048)
			(end 0.67945 -0.305054)
			(stroke
				(width 0.1)
				(type default)
			)
			(layer "B.Fab")
		)
		(fp_line
			(start 0.12065 0.3048)
			(end 0.67945 0.3048)
			(stroke
				(width 0.1)
				(type default)
			)
			(layer "B.Fab")
		)
		(fp_line
			(start -0.120396 0.3048)
			(end -0.120396 0.2794)
			(stroke
				(width 0.1)
				(type default)
			)
			(layer "B.Fab")
		)
		(fp_line
			(start -0.67945 0.3048)
			(end -0.120396 0.3048)
			(stroke
				(width 0.1)
				(type default)
			)
			(layer "B.Fab")
		)
		(pad "1" smd circle
			(at 0.40005 0 270)
			(size 0 0)
			(layers "B.Cu" "B.Mask" "B.Paste")
			(net "I3C_SPD_DDREFGH_CPU0_LVC1_SCL_2")
		)
		(pad "2" smd circle
			(at -0.40005 0 270)
			(size 0 0)
			(layers "B.Cu" "B.Mask" "B.Paste")
			(net "I3C_SPD_DDREFGH_CPU0_LVC1_SCL")
		)
	)
	(footprint ""
		(layer "B.Cu")
		(at 80.430624 -185.874152 90)
		(property "Reference" "R244"
			(at 0 0 90)
			(layer "B.SilkS")
			(hide yes)
			(effects
				(font
					(size 1.27 1.27)
				)
				(justify mirror)
			)
		)
		(property "Value" ""
			(at 0 0 90)
			(layer "B.Fab")
			(effects
				(font
					(size 1.27 1.27)
				)
				(justify mirror)
			)
		)
		(duplicate_pad_numbers_are_jumpers no)
		(fp_line
			(start 0.7874 -0.4064)
			(end -0.7874 -0.4064)
			(stroke
				(width 0.1524)
				(type default)
			)
			(layer "B.SilkS")
		)
		(fp_line
			(start -0.7874 -0.4064)
			(end -0.7874 0.4064)
			(stroke
				(width 0.1524)
				(type default)
			)
			(layer "B.SilkS")
		)
		(fp_line
			(start 0.7874 0.4064)
			(end 0.7874 -0.4064)
			(stroke
				(width 0.1524)
				(type default)
			)
			(layer "B.SilkS")
		)
		(fp_line
			(start -0.7874 0.4064)
			(end 0.7874 0.4064)
			(stroke
				(width 0.1524)
				(type default)
			)
			(layer "B.SilkS")
		)
		(fp_line
			(start 0.67945 -0.305054)
			(end 0.12065 -0.305054)
			(stroke
				(width 0.1)
				(type default)
			)
			(layer "B.Fab")
		)
		(fp_line
			(start 0.12065 -0.305054)
			(end 0.12065 -0.2794)
			(stroke
				(width 0.1)
				(type default)
			)
			(layer "B.Fab")
		)
		(fp_line
			(start -0.12065 -0.3048)
			(end -0.67945 -0.3048)
			(stroke
				(width 0.1)
				(type default)
			)
			(layer "B.Fab")
		)
		(fp_line
			(start -0.67945 -0.3048)
			(end -0.67945 0.3048)
			(stroke
				(width 0.1)
				(type default)
			)
			(layer "B.Fab")
		)
		(fp_line
			(start 0.12065 -0.2794)
			(end -0.12065 -0.2794)
			(stroke
				(width 0.1)
				(type default)
			)
			(layer "B.Fab")
		)
		(fp_line
			(start -0.12065 -0.2794)
			(end -0.12065 -0.3048)
			(stroke
				(width 0.1)
				(type default)
			)
			(layer "B.Fab")
		)
		(fp_line
			(start 0.12065 0.2794)
			(end 0.12065 0.3048)
			(stroke
				(width 0.1)
				(type default)
			)
			(layer "B.Fab")
		)
		(fp_line
			(start -0.120396 0.2794)
			(end 0.12065 0.2794)
			(stroke
				(width 0.1)
				(type default)
			)
			(layer "B.Fab")
		)
		(fp_line
			(start 0.67945 0.3048)
			(end 0.67945 -0.305054)
			(stroke
				(width 0.1)
				(type default)
			)
			(layer "B.Fab")
		)
		(fp_line
			(start 0.12065 0.3048)
			(end 0.67945 0.3048)
			(stroke
				(width 0.1)
				(type default)
			)
			(layer "B.Fab")
		)
		(fp_line
			(start -0.120396 0.3048)
			(end -0.120396 0.2794)
			(stroke
				(width 0.1)
				(type default)
			)
			(layer "B.Fab")
		)
		(fp_line
			(start -0.67945 0.3048)
			(end -0.120396 0.3048)
			(stroke
				(width 0.1)
				(type default)
			)
			(layer "B.Fab")
		)
		(pad "1" smd circle
			(at 0.40005 0 270)
			(size 0 0)
			(layers "B.Cu" "B.Mask" "B.Paste")
			(net "PVNN_TERM_CPU1")
		)
		(pad "2" smd circle
			(at -0.40005 0 270)
			(size 0 0)
			(layers "B.Cu" "B.Mask" "B.Paste")
			(net "H_CPU1_PROCHOT_LVC1_N")
		)
	)
	(footprint ""
		(layer "B.Cu")
		(at 69.353684 -185.791856 90)
		(property "Reference" "R761"
			(at 0 0 90)
			(layer "B.SilkS")
			(hide yes)
			(effects
				(font
					(size 1.27 1.27)
				)
				(justify mirror)
			)
		)
		(property "Value" ""
			(at 0 0 90)
			(layer "B.Fab")
			(effects
				(font
					(size 1.27 1.27)
				)
				(justify mirror)
			)
		)
		(duplicate_pad_numbers_are_jumpers no)
		(fp_line
			(start 0.7874 -0.4064)
			(end -0.7874 -0.4064)
			(stroke
				(width 0.1524)
				(type default)
			)
			(layer "B.SilkS")
		)
		(fp_line
			(start -0.7874 -0.4064)
			(end -0.7874 0.4064)
			(stroke
				(width 0.1524)
				(type default)
			)
			(layer "B.SilkS")
		)
		(fp_line
			(start 0.7874 0.4064)
			(end 0.7874 -0.4064)
			(stroke
				(width 0.1524)
				(type default)
			)
			(layer "B.SilkS")
		)
		(fp_line
			(start -0.7874 0.4064)
			(end 0.7874 0.4064)
			(stroke
				(width 0.1524)
				(type default)
			)
			(layer "B.SilkS")
		)
		(fp_line
			(start 0.67945 -0.305054)
			(end 0.12065 -0.305054)
			(stroke
				(width 0.1)
				(type default)
			)
			(layer "B.Fab")
		)
		(fp_line
			(start 0.12065 -0.305054)
			(end 0.12065 -0.2794)
			(stroke
				(width 0.1)
				(type default)
			)
			(layer "B.Fab")
		)
		(fp_line
			(start -0.12065 -0.3048)
			(end -0.67945 -0.3048)
			(stroke
				(width 0.1)
				(type default)
			)
			(layer "B.Fab")
		)
		(fp_line
			(start -0.67945 -0.3048)
			(end -0.67945 0.3048)
			(stroke
				(width 0.1)
				(type default)
			)
			(layer "B.Fab")
		)
		(fp_line
			(start 0.12065 -0.2794)
			(end -0.12065 -0.2794)
			(stroke
				(width 0.1)
				(type default)
			)
			(layer "B.Fab")
		)
		(fp_line
			(start -0.12065 -0.2794)
			(end -0.12065 -0.3048)
			(stroke
				(width 0.1)
				(type default)
			)
			(layer "B.Fab")
		)
		(fp_line
			(start 0.12065 0.2794)
			(end 0.12065 0.3048)
			(stroke
				(width 0.1)
				(type default)
			)
			(layer "B.Fab")
		)
		(fp_line
			(start -0.120396 0.2794)
			(end 0.12065 0.2794)
			(stroke
				(width 0.1)
				(type default)
			)
			(layer "B.Fab")
		)
		(fp_line
			(start 0.67945 0.3048)
			(end 0.67945 -0.305054)
			(stroke
				(width 0.1)
				(type default)
			)
			(layer "B.Fab")
		)
		(fp_line
			(start 0.12065 0.3048)
			(end 0.67945 0.3048)
			(stroke
				(width 0.1)
				(type default)
			)
			(layer "B.Fab")
		)
		(fp_line
			(start -0.120396 0.3048)
			(end -0.120396 0.2794)
			(stroke
				(width 0.1)
				(type default)
			)
			(layer "B.Fab")
		)
		(fp_line
			(start -0.67945 0.3048)
			(end -0.120396 0.3048)
			(stroke
				(width 0.1)
				(type default)
			)
			(layer "B.Fab")
		)
		(pad "1" smd circle
			(at 0.40005 0 270)
			(size 0 0)
			(layers "B.Cu" "B.Mask" "B.Paste")
			(net "PVNN_TERM_CPU0")
		)
		(pad "2" smd circle
			(at -0.40005 0 270)
			(size 0 0)
			(layers "B.Cu" "B.Mask" "B.Paste")
			(net "DBP_CPU_HOOK9_MBP3_GTL_QS_N")
		)
	)
)
